# T6G (Grand Teton) — schematic netlist excerpt (pin names and nets, part order shuffled) for the footprints in the layout excerpt that follows; sources: Cadence DE-HDL packaged netlist, KiCad conversion of 04192023_DAF0TMB3IC0_F0TG_MB_C_brd_V02_OCP.brd

C6658  Q_CAP_DIFFBUS  DIFF BUS_0.22UF 6.3V 20% X6S  pkg C0201  page 319 : \1\ = P5E_CPU1_P0_TX_BUF_C_DN<14> ; \2\ = P5E_CPU1_P0_TX_BUF_DN<14>
R8238  Q_RES  49.9 1% CHIP  pkg 0402LF  page 217 : A = SVID_PVDDCR_CPU1_P1_SVTO ; B = SVID_PVDDCR_CPU1_P1_SVTO_R
R1201  Q_RES  0 5% CHIP  pkg 0201LF  page 186 : A = RST_SMB_RT_ROM_R1_N ; B = FM_SMB_RT_ROM_MUX1_SEL

(kicad_pcb
	(version 20260206)
	(generator "pcbnew")
	(generator_version "10.0")
	(general
		(thickness 1.6)
		(legacy_teardrops no)
	)
	(paper "A4")
	(title_block
		(title "04192023_DAF0TMB3IC0_F0TG_MB_C_brd_V02_OCP.brd")
		(comment 1 "Grand Teton / footprints 2746-2748 of 8354")
	)
	(layers
		(0 "F.Cu" signal "TOP")
		(4 "In1.Cu" signal "GND")
		(6 "In2.Cu" signal "IN1")
		(8 "In3.Cu" signal "GND1")
		(10 "In4.Cu" signal "IN2")
		(12 "In5.Cu" signal "GND2")
		(14 "In6.Cu" signal "IN3")
		(16 "In7.Cu" signal "GND3")
		(18 "In8.Cu" signal "VCC")
		(20 "In9.Cu" signal "VCC1")
		(22 "In10.Cu" signal "GND4")
		(24 "In11.Cu" signal "IN4")
		(26 "In12.Cu" signal "GND5")
		(28 "In13.Cu" signal "IN5")
		(30 "In14.Cu" signal "GND6")
		(32 "In15.Cu" signal "IN6")
		(34 "In16.Cu" signal "GND7")
		(2 "B.Cu" signal "BOTTOM")
		(9 "F.Adhes" user "F.Adhesive")
		(11 "B.Adhes" user "B.Adhesive")
		(13 "F.Paste" user "Package Geometry/Pastemask Top")
		(15 "B.Paste" user "Package Geometry/Pastemask Bottom")
		(5 "F.SilkS" user "Ref Des/Silkscreen Top")
		(7 "B.SilkS" user "Ref Des/Silkscreen Bottom")
		(1 "F.Mask" user "Board Geometry/Soldermask Top")
		(3 "B.Mask" user "Board Geometry/Soldermask Bottom")
		(17 "Dwgs.User" user "User.Drawings")
		(19 "Cmts.User" user "User.Comments")
		(21 "Eco1.User" user "User.Eco1")
		(23 "Eco2.User" user "User.Eco2")
		(25 "Edge.Cuts" user "Board Geometry/Outline")
		(27 "Margin" user)
		(31 "F.CrtYd" user "Package Geometry/Place Bound Top")
		(29 "B.CrtYd" user "Package Geometry/Place Bound Bottom")
		(35 "F.Fab" user "Ref Des/Assembly Top")
		(33 "B.Fab" user "Ref Des/Assembly Bottom")
	)
	(footprint ""
		(layer "F.Cu")
		(at 24.765 -358.775)
		(property "Reference" "R8238"
			(at 0 0 0)
			(layer "F.SilkS")
			(hide yes)
			(effects
				(font
					(size 1.27 1.27)
				)
			)
		)
		(property "Value" ""
			(at 0 0 0)
			(layer "F.Fab")
			(effects
				(font
					(size 1.27 1.27)
				)
			)
		)
		(duplicate_pad_numbers_are_jumpers no)
		(fp_line
			(start -0.7874 -0.4064)
			(end 0.7874 -0.4064)
			(stroke
				(width 0.1524)
				(type default)
			)
			(layer "F.SilkS")
		)
		(fp_line
			(start -0.7874 0.4064)
			(end -0.7874 -0.4064)
			(stroke
				(width 0.1524)
				(type default)
			)
			(layer "F.SilkS")
		)
		(fp_line
			(start 0.7874 -0.4064)
			(end 0.7874 0.4064)
			(stroke
				(width 0.1524)
				(type default)
			)
			(layer "F.SilkS")
		)
		(fp_line
			(start 0.7874 0.4064)
			(end -0.7874 0.4064)
			(stroke
				(width 0.1524)
				(type default)
			)
			(layer "F.SilkS")
		)
		(fp_line
			(start -0.67945 -0.305054)
			(end -0.12065 -0.305054)
			(stroke
				(width 0.1)
				(type default)
			)
			(layer "F.Fab")
		)
		(fp_line
			(start -0.67945 0.3048)
			(end -0.67945 -0.305054)
			(stroke
				(width 0.1)
				(type default)
			)
			(layer "F.Fab")
		)
		(fp_line
			(start -0.12065 -0.305054)
			(end -0.12065 -0.2794)
			(stroke
				(width 0.1)
				(type default)
			)
			(layer "F.Fab")
		)
		(fp_line
			(start -0.12065 -0.2794)
			(end 0.12065 -0.2794)
			(stroke
				(width 0.1)
				(type default)
			)
			(layer "F.Fab")
		)
		(fp_line
			(start -0.12065 0.2794)
			(end -0.12065 0.3048)
			(stroke
				(width 0.1)
				(type default)
			)
			(layer "F.Fab")
		)
		(fp_line
			(start -0.12065 0.3048)
			(end -0.67945 0.3048)
			(stroke
				(width 0.1)
				(type default)
			)
			(layer "F.Fab")
		)
		(fp_line
			(start 0.120396 0.2794)
			(end -0.12065 0.2794)
			(stroke
				(width 0.1)
				(type default)
			)
			(layer "F.Fab")
		)
		(fp_line
			(start 0.120396 0.3048)
			(end 0.120396 0.2794)
			(stroke
				(width 0.1)
				(type default)
			)
			(layer "F.Fab")
		)
		(fp_line
			(start 0.12065 -0.3048)
			(end 0.67945 -0.3048)
			(stroke
				(width 0.1)
				(type default)
			)
			(layer "F.Fab")
		)
		(fp_line
			(start 0.12065 -0.2794)
			(end 0.12065 -0.3048)
			(stroke
				(width 0.1)
				(type default)
			)
			(layer "F.Fab")
		)
		(fp_line
			(start 0.67945 -0.3048)
			(end 0.67945 0.3048)
			(stroke
				(width 0.1)
				(type default)
			)
			(layer "F.Fab")
		)
		(fp_line
			(start 0.67945 0.3048)
			(end 0.120396 0.3048)
			(stroke
				(width 0.1)
				(type default)
			)
			(layer "F.Fab")
		)
		(pad "1" smd circle
			(at -0.40005 0)
			(size 0 0)
			(layers "F.Cu" "F.Mask" "F.Paste")
			(net "SVID_PVDDCR_CPU1_P1_SVTO")
		)
		(pad "2" smd circle
			(at 0.40005 0)
			(size 0 0)
			(layers "F.Cu" "F.Mask" "F.Paste")
			(net "SVID_PVDDCR_CPU1_P1_SVTO_R")
		)
	)
	(footprint ""
		(layer "F.Cu")
		(at 90.654124 -408.517344 -90)
		(property "Reference" "C6658"
			(at 0 0 270)
			(layer "F.SilkS")
			(hide yes)
			(effects
				(font
					(size 1.27 1.27)
				)
			)
		)
		(property "Value" ""
			(at 0 0 270)
			(layer "F.Fab")
			(effects
				(font
					(size 1.27 1.27)
				)
			)
		)
		(duplicate_pad_numbers_are_jumpers no)
		(fp_line
			(start -0.299974 0.150114)
			(end -0.299974 -0.150114)
			(stroke
				(width 0.1)
				(type default)
			)
			(layer "F.Fab")
		)
		(fp_line
			(start 0.299974 0.150114)
			(end -0.299974 0.150114)
			(stroke
				(width 0.1)
				(type default)
			)
			(layer "F.Fab")
		)
		(fp_line
			(start -0.299974 -0.150114)
			(end 0.299974 -0.150114)
			(stroke
				(width 0.1)
				(type default)
			)
			(layer "F.Fab")
		)
		(fp_line
			(start 0.299974 -0.150114)
			(end 0.299974 0.150114)
			(stroke
				(width 0.1)
				(type default)
			)
			(layer "F.Fab")
		)
		(pad "1" smd rect
			(at -0.2667 0 270)
			(size 0.3048 0.381)
			(layers "F.Cu" "F.Mask" "F.Paste")
			(net "P5E_CPU1_P0_TX_BUF_C_DN<14>")
		)
		(pad "2" smd rect
			(at 0.2667 0 270)
			(size 0.3048 0.381)
			(layers "F.Cu" "F.Mask" "F.Paste")
			(net "P5E_CPU1_P0_TX_BUF_DN<14>")
		)
	)
	(footprint ""
		(layer "F.Cu")
		(at 100.332286 -402.917406 -90)
		(property "Reference" "R1201"
			(at 0 0 270)
			(layer "F.SilkS")
			(hide yes)
			(effects
				(font
					(size 1.27 1.27)
				)
			)
		)
		(property "Value" ""
			(at 0 0 270)
			(layer "F.Fab")
			(effects
				(font
					(size 1.27 1.27)
				)
			)
		)
		(duplicate_pad_numbers_are_jumpers no)
		(fp_line
			(start -0.32512 0.175006)
			(end -0.32512 -0.175006)
			(stroke
				(width 0.1)
				(type default)
			)
			(layer "F.Fab")
		)
		(fp_line
			(start 0.32512 0.175006)
			(end -0.32512 0.175006)
			(stroke
				(width 0.1)
				(type default)
			)
			(layer "F.Fab")
		)
		(fp_line
			(start -0.32512 -0.175006)
			(end 0.32512 -0.175006)
			(stroke
				(width 0.1)
				(type default)
			)
			(layer "F.Fab")
		)
		(fp_line
			(start 0.32512 -0.175006)
			(end 0.32512 0.175006)
			(stroke
				(width 0.1)
				(type default)
			)
			(layer "F.Fab")
		)
		(pad "1" smd rect
			(at -0.2667 0 270)
			(size 0.3048 0.381)
			(layers "F.Cu" "F.Mask" "F.Paste")
			(net "RST_SMB_RT_ROM_R1_N")
		)
		(pad "2" smd rect
			(at 0.2667 0 90)
			(size 0.3048 0.381)
			(layers "F.Cu" "F.Mask" "F.Paste")
			(net "FM_SMB_RT_ROM_MUX1_SEL")
		)
	)
)
